# T6G (Grand Teton) — schematic netlist excerpt (pin names and nets, part order shuffled) for the footprints in the layout excerpt that follows; sources: Cadence DE-HDL packaged netlist, KiCad conversion of 04192023_DAF0TMB3IC0_F0TG_MB_C_brd_V02_OCP.brd

C727  Q_CAP_DIFFBUS  DIFF BUS_0.22UF 6.3V 20% X6S  pkg C0201  page 66 : \1\ = P5E_CPU1_P1_TX_C_DP<7> ; \2\ = P5E_CPU1_P1_TX_DP<7>
PC6561  Q_CAPP  100UF 16V 20% OSCON  pkg SMLF  page 363 : A = SW_P12V_AUX_P0V9_RETIMER_CPU0_FLT ; B = GND
C1556  Q_CAP_DIFFBUS  DIFF BUS_0.22UF 6.3V 20% X6S  pkg C0201  page 65 : \1\ = P5E_CPU0_G3_TX_C_DN<11> ; \2\ = P5E_CPU0_G3_TX_DN<11>
R6306  Q_RES  4.7K 1% CHIP  pkg 0402LF  page 179 : A = P3V3_AUX ; B = USB_HUB2_TI_HS_SUSPEND

(kicad_pcb
	(version 20260206)
	(generator "pcbnew")
	(generator_version "10.0")
	(general
		(thickness 1.6)
		(legacy_teardrops no)
	)
	(paper "A4")
	(title_block
		(title "04192023_DAF0TMB3IC0_F0TG_MB_C_brd_V02_OCP.brd")
		(comment 1 "Grand Teton / footprints 880-883 of 8354")
	)
	(layers
		(0 "F.Cu" signal "TOP")
		(4 "In1.Cu" signal "GND")
		(6 "In2.Cu" signal "IN1")
		(8 "In3.Cu" signal "GND1")
		(10 "In4.Cu" signal "IN2")
		(12 "In5.Cu" signal "GND2")
		(14 "In6.Cu" signal "IN3")
		(16 "In7.Cu" signal "GND3")
		(18 "In8.Cu" signal "VCC")
		(20 "In9.Cu" signal "VCC1")
		(22 "In10.Cu" signal "GND4")
		(24 "In11.Cu" signal "IN4")
		(26 "In12.Cu" signal "GND5")
		(28 "In13.Cu" signal "IN5")
		(30 "In14.Cu" signal "GND6")
		(32 "In15.Cu" signal "IN6")
		(34 "In16.Cu" signal "GND7")
		(2 "B.Cu" signal "BOTTOM")
		(9 "F.Adhes" user "F.Adhesive")
		(11 "B.Adhes" user "B.Adhesive")
		(13 "F.Paste" user "Package Geometry/Pastemask Top")
		(15 "B.Paste" user "Package Geometry/Pastemask Bottom")
		(5 "F.SilkS" user "Ref Des/Silkscreen Top")
		(7 "B.SilkS" user "Ref Des/Silkscreen Bottom")
		(1 "F.Mask" user "Board Geometry/Soldermask Top")
		(3 "B.Mask" user "Board Geometry/Soldermask Bottom")
		(17 "Dwgs.User" user "User.Drawings")
		(19 "Cmts.User" user "User.Comments")
		(21 "Eco1.User" user "User.Eco1")
		(23 "Eco2.User" user "User.Eco2")
		(25 "Edge.Cuts" user "Board Geometry/Outline")
		(27 "Margin" user)
		(31 "F.CrtYd" user "Package Geometry/Place Bound Top")
		(29 "B.CrtYd" user "Package Geometry/Place Bound Bottom")
		(35 "F.Fab" user "Ref Des/Assembly Top")
		(33 "B.Fab" user "Ref Des/Assembly Bottom")
	)
	(footprint ""
		(layer "F.Cu")
		(at 87.430102 -375.49963 -90)
		(property "Reference" "C727"
			(at 0 0 270)
			(layer "F.SilkS")
			(hide yes)
			(effects
				(font
					(size 1.27 1.27)
				)
			)
		)
		(property "Value" ""
			(at 0 0 270)
			(layer "F.Fab")
			(effects
				(font
					(size 1.27 1.27)
				)
			)
		)
		(duplicate_pad_numbers_are_jumpers no)
		(fp_line
			(start -0.299974 0.150114)
			(end -0.299974 -0.150114)
			(stroke
				(width 0.1)
				(type default)
			)
			(layer "F.Fab")
		)
		(fp_line
			(start 0.299974 0.150114)
			(end -0.299974 0.150114)
			(stroke
				(width 0.1)
				(type default)
			)
			(layer "F.Fab")
		)
		(fp_line
			(start -0.299974 -0.150114)
			(end 0.299974 -0.150114)
			(stroke
				(width 0.1)
				(type default)
			)
			(layer "F.Fab")
		)
		(fp_line
			(start 0.299974 -0.150114)
			(end 0.299974 0.150114)
			(stroke
				(width 0.1)
				(type default)
			)
			(layer "F.Fab")
		)
		(pad "1" smd rect
			(at -0.2667 0 270)
			(size 0.3048 0.381)
			(layers "F.Cu" "F.Mask" "F.Paste")
			(net "P5E_CPU1_P1_TX_C_DP<7>")
		)
		(pad "2" smd rect
			(at 0.2667 0 270)
			(size 0.3048 0.381)
			(layers "F.Cu" "F.Mask" "F.Paste")
			(net "P5E_CPU1_P1_TX_DP<7>")
		)
	)
	(footprint ""
		(layer "F.Cu")
		(at 109.549946 -54.882034 -90)
		(property "Reference" "R6306"
			(at 0 0 270)
			(layer "F.SilkS")
			(hide yes)
			(effects
				(font
					(size 1.27 1.27)
				)
			)
		)
		(property "Value" ""
			(at 0 0 270)
			(layer "F.Fab")
			(effects
				(font
					(size 1.27 1.27)
				)
			)
		)
		(duplicate_pad_numbers_are_jumpers no)
		(fp_line
			(start -0.7874 0.4064)
			(end -0.7874 -0.4064)
			(stroke
				(width 0.1524)
				(type default)
			)
			(layer "F.SilkS")
		)
		(fp_line
			(start 0.7874 0.4064)
			(end -0.7874 0.4064)
			(stroke
				(width 0.1524)
				(type default)
			)
			(layer "F.SilkS")
		)
		(fp_line
			(start -0.7874 -0.4064)
			(end 0.7874 -0.4064)
			(stroke
				(width 0.1524)
				(type default)
			)
			(layer "F.SilkS")
		)
		(fp_line
			(start 0.7874 -0.4064)
			(end 0.7874 0.4064)
			(stroke
				(width 0.1524)
				(type default)
			)
			(layer "F.SilkS")
		)
		(fp_line
			(start -0.67945 0.3048)
			(end -0.67945 -0.305054)
			(stroke
				(width 0.1)
				(type default)
			)
			(layer "F.Fab")
		)
		(fp_line
			(start -0.12065 0.3048)
			(end -0.67945 0.3048)
			(stroke
				(width 0.1)
				(type default)
			)
			(layer "F.Fab")
		)
		(fp_line
			(start 0.120396 0.3048)
			(end 0.120396 0.2794)
			(stroke
				(width 0.1)
				(type default)
			)
			(layer "F.Fab")
		)
		(fp_line
			(start 0.67945 0.3048)
			(end 0.120396 0.3048)
			(stroke
				(width 0.1)
				(type default)
			)
			(layer "F.Fab")
		)
		(fp_line
			(start -0.12065 0.2794)
			(end -0.12065 0.3048)
			(stroke
				(width 0.1)
				(type default)
			)
			(layer "F.Fab")
		)
		(fp_line
			(start 0.120396 0.2794)
			(end -0.12065 0.2794)
			(stroke
				(width 0.1)
				(type default)
			)
			(layer "F.Fab")
		)
		(fp_line
			(start -0.12065 -0.2794)
			(end 0.12065 -0.2794)
			(stroke
				(width 0.1)
				(type default)
			)
			(layer "F.Fab")
		)
		(fp_line
			(start 0.12065 -0.2794)
			(end 0.12065 -0.3048)
			(stroke
				(width 0.1)
				(type default)
			)
			(layer "F.Fab")
		)
		(fp_line
			(start 0.12065 -0.3048)
			(end 0.67945 -0.3048)
			(stroke
				(width 0.1)
				(type default)
			)
			(layer "F.Fab")
		)
		(fp_line
			(start 0.67945 -0.3048)
			(end 0.67945 0.3048)
			(stroke
				(width 0.1)
				(type default)
			)
			(layer "F.Fab")
		)
		(fp_line
			(start -0.67945 -0.305054)
			(end -0.12065 -0.305054)
			(stroke
				(width 0.1)
				(type default)
			)
			(layer "F.Fab")
		)
		(fp_line
			(start -0.12065 -0.305054)
			(end -0.12065 -0.2794)
			(stroke
				(width 0.1)
				(type default)
			)
			(layer "F.Fab")
		)
		(pad "1" smd circle
			(at -0.40005 0 270)
			(size 0 0)
			(layers "F.Cu" "F.Mask" "F.Paste")
			(net "P3V3_AUX")
		)
		(pad "2" smd circle
			(at 0.40005 0 270)
			(size 0 0)
			(layers "F.Cu" "F.Mask" "F.Paste")
			(net "USB_HUB2_TI_HS_SUSPEND")
		)
	)
	(footprint ""
		(layer "F.Cu")
		(at 401.183348 -16.100298 90)
		(property "Reference" "C1556"
			(at 0 0 90)
			(layer "F.SilkS")
			(hide yes)
			(effects
				(font
					(size 1.27 1.27)
				)
			)
		)
		(property "Value" ""
			(at 0 0 90)
			(layer "F.Fab")
			(effects
				(font
					(size 1.27 1.27)
				)
			)
		)
		(duplicate_pad_numbers_are_jumpers no)
		(fp_line
			(start 0.299974 -0.150114)
			(end 0.299974 0.150114)
			(stroke
				(width 0.1)
				(type default)
			)
			(layer "F.Fab")
		)
		(fp_line
			(start -0.299974 -0.150114)
			(end 0.299974 -0.150114)
			(stroke
				(width 0.1)
				(type default)
			)
			(layer "F.Fab")
		)
		(fp_line
			(start 0.299974 0.150114)
			(end -0.299974 0.150114)
			(stroke
				(width 0.1)
				(type default)
			)
			(layer "F.Fab")
		)
		(fp_line
			(start -0.299974 0.150114)
			(end -0.299974 -0.150114)
			(stroke
				(width 0.1)
				(type default)
			)
			(layer "F.Fab")
		)
		(pad "1" smd rect
			(at -0.2667 0 90)
			(size 0.3048 0.381)
			(layers "F.Cu" "F.Mask" "F.Paste")
			(net "P5E_CPU0_G3_TX_C_DN<11>")
		)
		(pad "2" smd rect
			(at 0.2667 0 90)
			(size 0.3048 0.381)
			(layers "F.Cu" "F.Mask" "F.Paste")
			(net "P5E_CPU0_G3_TX_DN<11>")
		)
	)
	(footprint ""
		(layer "F.Cu")
		(at 445.467994 -411.8991 180)
		(property "Reference" "PC6561"
			(at 2.745994 3.49123 0)
			(unlocked yes)
			(layer "F.SilkS")
			(effects
				(font
					(size 0.7874 0.5842)
					(thickness 0.1524)
				)
				(justify left)
			)
		)
		(property "Value" ""
			(at 0 0 180)
			(layer "F.Fab")
			(effects
				(font
					(size 1.27 1.27)
				)
			)
		)
		(duplicate_pad_numbers_are_jumpers no)
		(fp_line
			(start 2.750058 2.750058)
			(end 2.750058 0.9398)
			(stroke
				(width 0.1524)
				(type default)
			)
			(layer "F.SilkS")
		)
		(fp_line
			(start 2.750058 -0.9398)
			(end 2.750058 -2.750058)
			(stroke
				(width 0.1524)
				(type default)
			)
			(layer "F.SilkS")
		)
		(fp_line
			(start 2.750058 -2.750058)
			(end -1.988058 -2.750058)
			(stroke
				(width 0.1524)
				(type default)
			)
			(layer "F.SilkS")
		)
		(fp_line
			(start -1.988058 2.750058)
			(end 2.750058 2.750058)
			(stroke
				(width 0.1524)
				(type default)
			)
			(layer "F.SilkS")
		)
		(fp_line
			(start -1.988058 -2.750058)
			(end -2.750058 -1.988058)
			(stroke
				(width 0.1524)
				(type default)
			)
			(layer "F.SilkS")
		)
		(fp_line
			(start -2.750058 1.988058)
			(end -1.988058 2.750058)
			(stroke
				(width 0.1524)
				(type default)
			)
			(layer "F.SilkS")
		)
		(fp_line
			(start -2.750058 0.9398)
			(end -2.750058 1.988058)
			(stroke
				(width 0.1524)
				(type default)
			)
			(layer "F.SilkS")
		)
		(fp_line
			(start -2.750058 -1.988058)
			(end -2.750058 -0.9398)
			(stroke
				(width 0.1524)
				(type default)
			)
			(layer "F.SilkS")
		)
		(fp_line
			(start 2.750058 2.750058)
			(end 2.750058 -2.750058)
			(stroke
				(width 0.1)
				(type default)
			)
			(layer "F.Fab")
		)
		(fp_line
			(start 2.750058 -2.750058)
			(end -2.750058 -2.750058)
			(stroke
				(width 0.1)
				(type default)
			)
			(layer "F.Fab")
		)
		(fp_line
			(start -2.750058 2.750058)
			(end 2.750058 2.750058)
			(stroke
				(width 0.1)
				(type default)
			)
			(layer "F.Fab")
		)
		(fp_line
			(start -2.750058 -2.750058)
			(end -2.750058 2.750058)
			(stroke
				(width 0.1)
				(type default)
			)
			(layer "F.Fab")
		)
		(pad "1" smd rect
			(at -2.199894 0 270)
			(size 1.6002 3.0226)
			(layers "F.Cu" "F.Mask" "F.Paste")
			(net "SW_P12V_AUX_P0V9_RETIMER_CPU0_FLT")
		)
		(pad "2" smd rect
			(at 2.199894 0 270)
			(size 1.6002 3.0226)
			(layers "F.Cu" "F.Mask" "F.Paste")
			(net "GND")
		)
	)
)
